(kicad_pcb
	(version 20260206)
	(generator "pcbnew")
	(generator_version "10.0")
	(general
		(thickness 1.6)
		(legacy_teardrops no)
	)
	(paper "A4")
	(title_block
		(title "netronome-mezz — pcbd0082-001_rev01_jul9_a.brd")
		(comment 1 "Open CloudServer (Microsoft) / footprints 129-138 of 714")
	)
	(layers
		(0 "F.Cu" signal "TOP")
		(4 "In1.Cu" signal "02_GND")
		(6 "In2.Cu" signal "03_SIG")
		(8 "In3.Cu" signal "04_SIG")
		(10 "In4.Cu" signal "05_GND")
		(12 "In5.Cu" signal "06_PWR1")
		(14 "In6.Cu" signal "07_SIG")
		(16 "In7.Cu" signal "08_SIG")
		(18 "In8.Cu" signal "09_GND")
		(2 "B.Cu" signal "BOTTOM")
		(9 "F.Adhes" user "F.Adhesive")
		(11 "B.Adhes" user "B.Adhesive")
		(13 "F.Paste" user "Package Geometry/Pastemask Top")
		(15 "B.Paste" user "Package Geometry/Pastemask Bottom")
		(5 "F.SilkS" user "Ref Des/Silkscreen Top")
		(7 "B.SilkS" user "Ref Des/Silkscreen Bottom")
		(1 "F.Mask" user "Board Geometry/Soldermask Top")
		(3 "B.Mask" user "Board Geometry/Soldermask Bottom")
		(17 "Dwgs.User" user "User.Drawings")
		(19 "Cmts.User" user "User.Comments")
		(21 "Eco1.User" user "User.Eco1")
		(23 "Eco2.User" user "User.Eco2")
		(25 "Edge.Cuts" user "Board Geometry/Outline")
		(27 "Margin" user)
		(31 "F.CrtYd" user "Package Geometry/Place Bound Top")
		(29 "B.CrtYd" user "Package Geometry/Place Bound Bottom")
		(35 "F.Fab" user "Ref Des/Assembly Top")
		(33 "B.Fab" user "Ref Des/Assembly Bottom")
		(45 "User.4" user "COMPVAL_TYPE_BOTTOM")
	)
	(footprint ""
		(layer "F.Cu")
		(at 35.433 32.639)
		(property "Reference" "R80"
			(at 0 0 0)
			(layer "F.SilkS")
			(hide yes)
			(effects
				(font
					(size 1.27 1.27)
				)
			)
		)
		(property "Value" "4.75K"
			(at -0.148158 1.3462 90)
			(unlocked yes)
			(layer "F.Fab")
			(hide yes)
			(effects
				(font
					(size 1.27 0.9652)
					(thickness 0.000001)
				)
				(justify left)
			)
		)
		(property "Device Type" "REST4024"
			(at -0.148158 1.3462 90)
			(unlocked yes)
			(layer "F.Fab")
			(hide yes)
			(effects
				(font
					(size 1.27 0.9652)
					(thickness 0.000001)
				)
				(justify left)
			)
		)
		(duplicate_pad_numbers_are_jumpers no)
		(fp_poly
			(pts
				(xy 0.635 1.0668) (xy 0.635 -1.0668) (xy -0.635 -1.0668) (xy -0.635 1.0668)
			)
			(stroke
				(width 0)
				(type default)
			)
			(fill no)
			(layer "F.CrtYd")
		)
		(fp_line
			(start -0.254 -0.508)
			(end 0.254 -0.508)
			(stroke
				(width 0.0254)
				(type default)
			)
			(layer "F.Fab")
		)
		(fp_line
			(start -0.254 0.508)
			(end -0.254 -0.508)
			(stroke
				(width 0.0254)
				(type default)
			)
			(layer "F.Fab")
		)
		(fp_line
			(start 0.254 -0.508)
			(end 0.254 0.508)
			(stroke
				(width 0.0254)
				(type default)
			)
			(layer "F.Fab")
		)
		(fp_line
			(start 0.254 0.508)
			(end -0.254 0.508)
			(stroke
				(width 0.0254)
				(type default)
			)
			(layer "F.Fab")
		)
		(pad "1" smd rect
			(at 0 -0.4191)
			(size 0.508 0.5334)
			(layers "F.Cu" "F.Mask" "F.Paste")
			(net "GND")
		)
		(pad "2" smd rect
			(at 0 0.4191)
			(size 0.508 0.5334)
			(layers "F.Cu" "F.Mask" "F.Paste")
			(net "_NFP_CORE_VID6")
		)
		(zone
			(layer "F.Cu")
			(hatch none 0.5)
			(connect_pads
				(clearance 0)
			)
			(min_thickness 0.25)
			(keepout
				(tracks not_allowed)
				(vias allowed)
				(pads allowed)
				(copperpour not_allowed)
				(footprints allowed)
			)
			(placement
				(enabled no)
				(sheetname "")
			)
			(fill
				(thermal_gap 0.5)
				(thermal_bridge_width 0.5)
				(island_removal_mode 0)
			)
			(polygon
				(pts
					(xy 35.4584 32.6136) (xy 35.4584 32.6644) (xy 35.4076 32.6644) (xy 35.4076 32.6136)
				)
			)
		)
	)
	(footprint ""
		(layer "F.Cu")
		(at 80.645 20.574 -90)
		(property "Reference" "C215"
			(at -0.889 -0.53467 90)
			(unlocked yes)
			(layer "F.SilkS")
			(effects
				(font
					(size 0.7874 0.5842)
					(thickness 0.127)
				)
				(justify left)
			)
		)
		(property "Value" "1UF"
			(at -0.091846 0.2921 0)
			(unlocked yes)
			(layer "F.Fab")
			(hide yes)
			(effects
				(font
					(size 0.7874 0.5842)
					(thickness 0.2032)
				)
				(justify left)
			)
		)
		(property "Device Type" "CAPC0028"
			(at -0.091846 0.2921 0)
			(unlocked yes)
			(layer "F.Fab")
			(hide yes)
			(effects
				(font
					(size 0.7874 0.5842)
					(thickness 0.2032)
				)
				(justify left)
			)
		)
		(duplicate_pad_numbers_are_jumpers no)
		(fp_poly
			(pts
				(xy 0.635 1.0668) (xy 0.635 -1.0668) (xy -0.635 -1.0668) (xy -0.635 1.0668)
			)
			(stroke
				(width 0)
				(type default)
			)
			(fill no)
			(layer "F.CrtYd")
		)
		(fp_line
			(start -0.254 0.508)
			(end -0.254 -0.508)
			(stroke
				(width 0.0254)
				(type default)
			)
			(layer "F.Fab")
		)
		(fp_line
			(start 0.254 0.508)
			(end -0.254 0.508)
			(stroke
				(width 0.0254)
				(type default)
			)
			(layer "F.Fab")
		)
		(fp_line
			(start -0.254 -0.508)
			(end 0.254 -0.508)
			(stroke
				(width 0.0254)
				(type default)
			)
			(layer "F.Fab")
		)
		(fp_line
			(start 0.254 -0.508)
			(end 0.254 0.508)
			(stroke
				(width 0.0254)
				(type default)
			)
			(layer "F.Fab")
		)
		(pad "1" smd rect
			(at 0 -0.4191 270)
			(size 0.508 0.5334)
			(layers "F.Cu" "F.Mask" "F.Paste")
			(net "DDR_VDDQ")
		)
		(pad "2" smd rect
			(at 0 0.4191 270)
			(size 0.508 0.5334)
			(layers "F.Cu" "F.Mask" "F.Paste")
			(net "GND")
		)
		(zone
			(layer "F.Cu")
			(hatch none 0.5)
			(connect_pads
				(clearance 0)
			)
			(min_thickness 0.25)
			(keepout
				(tracks not_allowed)
				(vias allowed)
				(pads allowed)
				(copperpour not_allowed)
				(footprints allowed)
			)
			(placement
				(enabled no)
				(sheetname "")
			)
			(fill
				(thermal_gap 0.5)
				(thermal_bridge_width 0.5)
				(island_removal_mode 0)
			)
			(polygon
				(pts
					(xy 80.6704 20.5994) (xy 80.6196 20.5994) (xy 80.6196 20.5486) (xy 80.6704 20.5486)
				)
			)
		)
	)
	(footprint ""
		(layer "F.Cu")
		(at 74.651006 18.255996)
		(property "Reference" "V_A-DM2"
			(at 0 0 0)
			(layer "F.SilkS")
			(hide yes)
			(effects
				(font
					(size 1.27 1.27)
				)
			)
		)
		(property "Value" ""
			(at 0 0 0)
			(layer "F.Fab")
			(effects
				(font
					(size 1.27 1.27)
				)
			)
		)
		(duplicate_pad_numbers_are_jumpers no)
		(pad "1" thru_hole circle
			(at 0 0)
			(size 0.762 0.762)
			(drill 0.20574)
			(layers "*.Cu" "*.Mask")
			(remove_unused_layers no)
			(net "DDR0_32A_DM2")
			(clearance 0.127)
			(thermal_gap 0.127)
			(padstack
				(mode front_inner_back)
				(layer "Inner"
					(shape circle)
					(size 0.4572 0.4572)
					(clearance 0.1143)
				)
				(layer "B.Cu"
					(shape circle)
					(size 0.4572 0.4572)
					(clearance 0.1143)
				)
			)
		)
	)
	(footprint ""
		(layer "F.Cu")
		(at 77.216 4.572)
		(property "Reference" "C206"
			(at 0 0 0)
			(layer "F.SilkS")
			(hide yes)
			(effects
				(font
					(size 1.27 1.27)
				)
			)
		)
		(property "Value" "1UF"
			(at -0.091846 0.2921 90)
			(unlocked yes)
			(layer "F.Fab")
			(hide yes)
			(effects
				(font
					(size 0.7874 0.5842)
					(thickness 0.2032)
				)
				(justify left)
			)
		)
		(property "Device Type" "CAPC0028"
			(at -0.091846 0.2921 90)
			(unlocked yes)
			(layer "F.Fab")
			(hide yes)
			(effects
				(font
					(size 0.7874 0.5842)
					(thickness 0.2032)
				)
				(justify left)
			)
		)
		(duplicate_pad_numbers_are_jumpers no)
		(fp_poly
			(pts
				(xy 0.635 1.0668) (xy 0.635 -1.0668) (xy -0.635 -1.0668) (xy -0.635 1.0668)
			)
			(stroke
				(width 0)
				(type default)
			)
			(fill no)
			(layer "F.CrtYd")
		)
		(fp_line
			(start -0.254 -0.508)
			(end 0.254 -0.508)
			(stroke
				(width 0.0254)
				(type default)
			)
			(layer "F.Fab")
		)
		(fp_line
			(start -0.254 0.508)
			(end -0.254 -0.508)
			(stroke
				(width 0.0254)
				(type default)
			)
			(layer "F.Fab")
		)
		(fp_line
			(start 0.254 -0.508)
			(end 0.254 0.508)
			(stroke
				(width 0.0254)
				(type default)
			)
			(layer "F.Fab")
		)
		(fp_line
			(start 0.254 0.508)
			(end -0.254 0.508)
			(stroke
				(width 0.0254)
				(type default)
			)
			(layer "F.Fab")
		)
		(pad "1" smd rect
			(at 0 -0.4191)
			(size 0.508 0.5334)
			(layers "F.Cu" "F.Mask" "F.Paste")
			(net "DDR0_32A_VREF0B")
		)
		(pad "2" smd rect
			(at 0 0.4191)
			(size 0.508 0.5334)
			(layers "F.Cu" "F.Mask" "F.Paste")
			(net "GND")
		)
		(zone
			(layer "F.Cu")
			(hatch none 0.5)
			(connect_pads
				(clearance 0)
			)
			(min_thickness 0.25)
			(keepout
				(tracks not_allowed)
				(vias allowed)
				(pads allowed)
				(copperpour not_allowed)
				(footprints allowed)
			)
			(placement
				(enabled no)
				(sheetname "")
			)
			(fill
				(thermal_gap 0.5)
				(thermal_bridge_width 0.5)
				(island_removal_mode 0)
			)
			(polygon
				(pts
					(xy 77.2414 4.5466) (xy 77.2414 4.5974) (xy 77.1906 4.5974) (xy 77.1906 4.5466)
				)
			)
		)
	)
	(footprint ""
		(layer "F.Cu")
		(at 33.655 32.639 180)
		(property "Reference" "R77"
			(at 0 0 180)
			(layer "F.SilkS")
			(hide yes)
			(effects
				(font
					(size 1.27 1.27)
				)
			)
		)
		(property "Value" "4.75K"
			(at -0.148158 1.3462 270)
			(unlocked yes)
			(layer "F.Fab")
			(hide yes)
			(effects
				(font
					(size 1.27 0.9652)
					(thickness 0.000001)
				)
				(justify left)
			)
		)
		(property "Device Type" "REST4024"
			(at -0.148158 1.3462 270)
			(unlocked yes)
			(layer "F.Fab")
			(hide yes)
			(effects
				(font
					(size 1.27 0.9652)
					(thickness 0.000001)
				)
				(justify left)
			)
		)
		(duplicate_pad_numbers_are_jumpers no)
		(fp_poly
			(pts
				(xy 0.635 1.0668) (xy 0.635 -1.0668) (xy -0.635 -1.0668) (xy -0.635 1.0668)
			)
			(stroke
				(width 0)
				(type default)
			)
			(fill no)
			(layer "F.CrtYd")
		)
		(fp_line
			(start 0.254 0.508)
			(end -0.254 0.508)
			(stroke
				(width 0.0254)
				(type default)
			)
			(layer "F.Fab")
		)
		(fp_line
			(start 0.254 -0.508)
			(end 0.254 0.508)
			(stroke
				(width 0.0254)
				(type default)
			)
			(layer "F.Fab")
		)
		(fp_line
			(start -0.254 0.508)
			(end -0.254 -0.508)
			(stroke
				(width 0.0254)
				(type default)
			)
			(layer "F.Fab")
		)
		(fp_line
			(start -0.254 -0.508)
			(end 0.254 -0.508)
			(stroke
				(width 0.0254)
				(type default)
			)
			(layer "F.Fab")
		)
		(pad "1" smd rect
			(at 0 -0.4191 180)
			(size 0.508 0.5334)
			(layers "F.Cu" "F.Mask" "F.Paste")
			(net "_NFP_CORE_VID5")
		)
		(pad "2" smd rect
			(at 0 0.4191 180)
			(size 0.508 0.5334)
			(layers "F.Cu" "F.Mask" "F.Paste")
			(net "VDD_1.2V")
		)
		(zone
			(layer "F.Cu")
			(hatch none 0.5)
			(connect_pads
				(clearance 0)
			)
			(min_thickness 0.25)
			(keepout
				(tracks not_allowed)
				(vias allowed)
				(pads allowed)
				(copperpour not_allowed)
				(footprints allowed)
			)
			(placement
				(enabled no)
				(sheetname "")
			)
			(fill
				(thermal_gap 0.5)
				(thermal_bridge_width 0.5)
				(island_removal_mode 0)
			)
			(polygon
				(pts
					(xy 33.6296 32.6644) (xy 33.6296 32.6136) (xy 33.6804 32.6136) (xy 33.6804 32.6644)
				)
			)
		)
	)
	(footprint ""
		(layer "F.Cu")
		(at 22.479 47.498)
		(property "Reference" "TP18"
			(at 1.67767 1.397 90)
			(unlocked yes)
			(layer "F.SilkS")
			(effects
				(font
					(size 0.7874 0.5842)
					(thickness 0.127)
				)
				(justify left)
			)
		)
		(property "Value" "*"
			(at -0.4826 -0.14732 0)
			(unlocked yes)
			(layer "F.Fab")
			(hide yes)
			(effects
				(font
					(size 1.27 0.9652)
					(thickness 0.000001)
				)
				(justify left)
			)
		)
		(property "Device Type" "TP_SMALL"
			(at -0.4826 -0.14732 0)
			(unlocked yes)
			(layer "F.Fab")
			(hide yes)
			(effects
				(font
					(size 1.27 0.9652)
					(thickness 0.000001)
				)
				(justify left)
			)
		)
		(duplicate_pad_numbers_are_jumpers no)
		(fp_line
			(start -0.8636 -0.8636)
			(end -0.8636 0.8636)
			(stroke
				(width 0.1524)
				(type default)
			)
			(layer "F.SilkS")
		)
		(fp_line
			(start -0.8636 0.8636)
			(end 0.8636 0.8636)
			(stroke
				(width 0.1524)
				(type default)
			)
			(layer "F.SilkS")
		)
		(fp_line
			(start 0.8636 -0.8636)
			(end -0.8636 -0.8636)
			(stroke
				(width 0.1524)
				(type default)
			)
			(layer "F.SilkS")
		)
		(fp_line
			(start 0.8636 0.8636)
			(end 0.8636 -0.8636)
			(stroke
				(width 0.1524)
				(type default)
			)
			(layer "F.SilkS")
		)
		(fp_poly
			(pts
				(xy -0.635 -0.635) (xy -0.635 0.635) (xy 0.635 0.635) (xy 0.635 -0.635)
			)
			(stroke
				(width 0)
				(type default)
			)
			(fill no)
			(layer "F.CrtYd")
		)
		(pad "1" smd rect
			(at 0 0)
			(size 1.27 1.27)
			(layers "F.Cu" "F.Mask" "F.Paste")
			(net "HOST_RESET_REQ_L")
		)
	)
	(footprint ""
		(layer "F.Cu")
		(at 33.274 48.641)
		(property "Reference" "TP61"
			(at 1.143 0.53467 0)
			(unlocked yes)
			(layer "F.SilkS")
			(effects
				(font
					(size 0.7874 0.5842)
					(thickness 0.127)
				)
				(justify left)
			)
		)
		(property "Value" "*"
			(at -0.4826 -0.14732 0)
			(unlocked yes)
			(layer "F.Fab")
			(hide yes)
			(effects
				(font
					(size 1.27 0.9652)
					(thickness 0.000001)
				)
				(justify left)
			)
		)
		(property "Device Type" "TP_SMALL"
			(at -0.4826 -0.14732 0)
			(unlocked yes)
			(layer "F.Fab")
			(hide yes)
			(effects
				(font
					(size 1.27 0.9652)
					(thickness 0.000001)
				)
				(justify left)
			)
		)
		(duplicate_pad_numbers_are_jumpers no)
		(fp_line
			(start -0.8636 -0.8636)
			(end -0.8636 0.8636)
			(stroke
				(width 0.1524)
				(type default)
			)
			(layer "F.SilkS")
		)
		(fp_line
			(start -0.8636 0.8636)
			(end 0.8636 0.8636)
			(stroke
				(width 0.1524)
				(type default)
			)
			(layer "F.SilkS")
		)
		(fp_line
			(start 0.8636 -0.8636)
			(end -0.8636 -0.8636)
			(stroke
				(width 0.1524)
				(type default)
			)
			(layer "F.SilkS")
		)
		(fp_line
			(start 0.8636 0.8636)
			(end 0.8636 -0.8636)
			(stroke
				(width 0.1524)
				(type default)
			)
			(layer "F.SilkS")
		)
		(fp_poly
			(pts
				(xy -0.635 -0.635) (xy -0.635 0.635) (xy 0.635 0.635) (xy 0.635 -0.635)
			)
			(stroke
				(width 0)
				(type default)
			)
			(fill no)
			(layer "F.CrtYd")
		)
		(pad "1" smd rect
			(at 0 0)
			(size 1.27 1.27)
			(layers "F.Cu" "F.Mask" "F.Paste")
			(net "VDD_5.0V_PGOOD")
		)
	)
	(footprint ""
		(layer "F.Cu")
		(at 84.6328 22.987 180)
		(property "Reference" "R213"
			(at 0.0508 -1.29667 0)
			(unlocked yes)
			(layer "F.SilkS")
			(effects
				(font
					(size 0.7874 0.5842)
					(thickness 0.127)
				)
				(justify left)
			)
		)
		(property "Value" "39.0"
			(at -0.148158 1.3462 270)
			(unlocked yes)
			(layer "F.Fab")
			(hide yes)
			(effects
				(font
					(size 1.27 0.9652)
					(thickness 0.000001)
				)
				(justify left)
			)
		)
		(property "Device Type" "REST0108"
			(at -0.148158 1.3462 270)
			(unlocked yes)
			(layer "F.Fab")
			(hide yes)
			(effects
				(font
					(size 1.27 0.9652)
					(thickness 0.000001)
				)
				(justify left)
			)
		)
		(duplicate_pad_numbers_are_jumpers no)
		(fp_poly
			(pts
				(xy 0.635 1.0668) (xy 0.635 -1.0668) (xy -0.635 -1.0668) (xy -0.635 1.0668)
			)
			(stroke
				(width 0)
				(type default)
			)
			(fill no)
			(layer "F.CrtYd")
		)
		(fp_line
			(start 0.254 0.508)
			(end -0.254 0.508)
			(stroke
				(width 0.0254)
				(type default)
			)
			(layer "F.Fab")
		)
		(fp_line
			(start 0.254 -0.508)
			(end 0.254 0.508)
			(stroke
				(width 0.0254)
				(type default)
			)
			(layer "F.Fab")
		)
		(fp_line
			(start -0.254 0.508)
			(end -0.254 -0.508)
			(stroke
				(width 0.0254)
				(type default)
			)
			(layer "F.Fab")
		)
		(fp_line
			(start -0.254 -0.508)
			(end 0.254 -0.508)
			(stroke
				(width 0.0254)
				(type default)
			)
			(layer "F.Fab")
		)
		(pad "1" smd rect
			(at 0 -0.4191 180)
			(size 0.508 0.5334)
			(layers "F.Cu" "F.Mask" "F.Paste")
			(net "DDR0_32A_A7")
		)
		(pad "2" smd rect
			(at 0 0.4191 180)
			(size 0.508 0.5334)
			(layers "F.Cu" "F.Mask" "F.Paste")
			(net "DDR_VTT")
		)
		(zone
			(layer "F.Cu")
			(hatch none 0.5)
			(connect_pads
				(clearance 0)
			)
			(min_thickness 0.25)
			(keepout
				(tracks not_allowed)
				(vias allowed)
				(pads allowed)
				(copperpour not_allowed)
				(footprints allowed)
			)
			(placement
				(enabled no)
				(sheetname "")
			)
			(fill
				(thermal_gap 0.5)
				(thermal_bridge_width 0.5)
				(island_removal_mode 0)
			)
			(polygon
				(pts
					(xy 84.6074 23.0124) (xy 84.6074 22.9616) (xy 84.6582 22.9616) (xy 84.6582 23.0124)
				)
			)
		)
	)
	(footprint ""
		(layer "F.Cu")
		(at 7.493 47.752 -90)
		(property "Reference" "TP45"
			(at 1.55067 -0.508 0)
			(unlocked yes)
			(layer "F.SilkS")
			(effects
				(font
					(size 0.7874 0.5842)
					(thickness 0.127)
				)
				(justify left)
			)
		)
		(property "Value" "*"
			(at -0.4826 -0.14732 270)
			(unlocked yes)
			(layer "F.Fab")
			(hide yes)
			(effects
				(font
					(size 1.27 0.9652)
					(thickness 0.000001)
				)
				(justify left)
			)
		)
		(property "Device Type" "TP_SMALL"
			(at -0.4826 -0.14732 270)
			(unlocked yes)
			(layer "F.Fab")
			(hide yes)
			(effects
				(font
					(size 1.27 0.9652)
					(thickness 0.000001)
				)
				(justify left)
			)
		)
		(duplicate_pad_numbers_are_jumpers no)
		(fp_line
			(start -0.8636 0.8636)
			(end 0.8636 0.8636)
			(stroke
				(width 0.1524)
				(type default)
			)
			(layer "F.SilkS")
		)
		(fp_line
			(start 0.8636 0.8636)
			(end 0.8636 -0.8636)
			(stroke
				(width 0.1524)
				(type default)
			)
			(layer "F.SilkS")
		)
		(fp_line
			(start -0.8636 -0.8636)
			(end -0.8636 0.8636)
			(stroke
				(width 0.1524)
				(type default)
			)
			(layer "F.SilkS")
		)
		(fp_line
			(start 0.8636 -0.8636)
			(end -0.8636 -0.8636)
			(stroke
				(width 0.1524)
				(type default)
			)
			(layer "F.SilkS")
		)
		(fp_poly
			(pts
				(xy -0.635 -0.635) (xy -0.635 0.635) (xy 0.635 0.635) (xy 0.635 -0.635)
			)
			(stroke
				(width 0)
				(type default)
			)
			(fill no)
			(layer "F.CrtYd")
		)
		(pad "1" smd rect
			(at 0 0 270)
			(size 1.27 1.27)
			(layers "F.Cu" "F.Mask" "F.Paste")
			(net "GND")
		)
	)
	(footprint ""
		(layer "F.Cu")
		(at 45.085 51.816 180)
		(property "Reference" "R316"
			(at 0 0 180)
			(layer "F.SilkS")
			(hide yes)
			(effects
				(font
					(size 1.27 1.27)
				)
			)
		)
		(property "Value" "1.0K"
			(at -0.148158 1.3462 270)
			(unlocked yes)
			(layer "F.Fab")
			(hide yes)
			(effects
				(font
					(size 1.27 0.9652)
					(thickness 0.000001)
				)
				(justify left)
			)
		)
		(property "Device Type" "REST0025"
			(at -0.148158 1.3462 270)
			(unlocked yes)
			(layer "F.Fab")
			(hide yes)
			(effects
				(font
					(size 1.27 0.9652)
					(thickness 0.000001)
				)
				(justify left)
			)
		)
		(duplicate_pad_numbers_are_jumpers no)
		(fp_poly
			(pts
				(xy 0.635 1.0668) (xy 0.635 -1.0668) (xy -0.635 -1.0668) (xy -0.635 1.0668)
			)
			(stroke
				(width 0)
				(type default)
			)
			(fill no)
			(layer "F.CrtYd")
		)
		(fp_line
			(start 0.254 0.508)
			(end -0.254 0.508)
			(stroke
				(width 0.0254)
				(type default)
			)
			(layer "F.Fab")
		)
		(fp_line
			(start 0.254 -0.508)
			(end 0.254 0.508)
			(stroke
				(width 0.0254)
				(type default)
			)
			(layer "F.Fab")
		)
		(fp_line
			(start -0.254 0.508)
			(end -0.254 -0.508)
			(stroke
				(width 0.0254)
				(type default)
			)
			(layer "F.Fab")
		)
		(fp_line
			(start -0.254 -0.508)
			(end 0.254 -0.508)
			(stroke
				(width 0.0254)
				(type default)
			)
			(layer "F.Fab")
		)
		(pad "1" smd rect
			(at 0 -0.4191 180)
			(size 0.508 0.5334)
			(layers "F.Cu" "F.Mask" "F.Paste")
			(net "GND")
		)
		(pad "2" smd rect
			(at 0 0.4191 180)
			(size 0.508 0.5334)
			(layers "F.Cu" "F.Mask" "F.Paste")
			(net "EXT_3.3V_THRESHOLD")
		)
		(zone
			(layer "F.Cu")
			(hatch none 0.5)
			(connect_pads
				(clearance 0)
			)
			(min_thickness 0.25)
			(keepout
				(tracks not_allowed)
				(vias allowed)
				(pads allowed)
				(copperpour not_allowed)
				(footprints allowed)
			)
			(placement
				(enabled no)
				(sheetname "")
			)
			(fill
				(thermal_gap 0.5)
				(thermal_bridge_width 0.5)
				(island_removal_mode 0)
			)
			(polygon
				(pts
					(xy 45.0596 51.8414) (xy 45.0596 51.7906) (xy 45.1104 51.7906) (xy 45.1104 51.8414)
				)
			)
		)
	)
)
